(kicad_pcb
	(version 20260206)
	(generator "pcbnew")
	(generator_version "10.0")
	(general
		(thickness 1.6)
		(legacy_teardrops no)
	)
	(paper "A4")
	(title_block
		(title "Wiwynn_Tioga_Pass_MB.brd")
		(comment 1 "Tioga Pass / footprints 1762-1768 of 4770")
	)
	(layers
		(0 "F.Cu" signal "TOP")
		(4 "In1.Cu" signal "L2GND")
		(6 "In2.Cu" signal "L3")
		(8 "In3.Cu" signal "L4GND")
		(10 "In4.Cu" signal "L5")
		(12 "In5.Cu" signal "L6GND")
		(14 "In6.Cu" signal "L7VCC")
		(16 "In7.Cu" signal "L8VCC")
		(18 "In8.Cu" signal "L9GND")
		(20 "In9.Cu" signal "L10")
		(22 "In10.Cu" signal "L11GND")
		(24 "In11.Cu" signal "L12")
		(26 "In12.Cu" signal "L13GND")
		(2 "B.Cu" signal "BOTTOM")
		(9 "F.Adhes" user "F.Adhesive")
		(11 "B.Adhes" user "B.Adhesive")
		(13 "F.Paste" user "Package Geometry/Pastemask Top")
		(15 "B.Paste" user "Package Geometry/Pastemask Bottom")
		(5 "F.SilkS" user "Ref Des/Silkscreen Top")
		(7 "B.SilkS" user "Ref Des/Silkscreen Bottom")
		(1 "F.Mask" user "Board Geometry/Soldermask Top")
		(3 "B.Mask" user "Board Geometry/Soldermask Bottom")
		(17 "Dwgs.User" user "User.Drawings")
		(19 "Cmts.User" user "User.Comments")
		(21 "Eco1.User" user "User.Eco1")
		(23 "Eco2.User" user "User.Eco2")
		(25 "Edge.Cuts" user "Board Geometry/Outline")
		(27 "Margin" user)
		(31 "F.CrtYd" user "Package Geometry/Place Bound Top")
		(29 "B.CrtYd" user "Package Geometry/Place Bound Bottom")
		(35 "F.Fab" user "Ref Des/Assembly Top")
		(33 "B.Fab" user "Ref Des/Assembly Bottom")
	)
	(footprint ""
		(layer "F.Cu")
		(at 435.388766 -43.086274 180)
		(property "Reference" "R25W30"
			(at -0.8382 -0.67818 180)
			(unlocked yes)
			(layer "F.SilkS")
			(effects
				(font
					(size 0.4064 0.254)
					(thickness 0.1524)
				)
				(justify left)
			)
		)
		(property "Value" ""
			(at 0 0 180)
			(layer "F.Fab")
			(effects
				(font
					(size 1.27 1.27)
				)
			)
		)
		(duplicate_pad_numbers_are_jumpers no)
		(fp_poly
			(pts
				(xy -0.2794 -0.1016) (xy 0.2794 -0.1016) (xy 0.2794 0.9906) (xy -0.2794 0.9906)
			)
			(stroke
				(width 0)
				(type default)
			)
			(fill no)
			(layer "F.CrtYd")
		)
		(fp_line
			(start 0.2794 0.9906)
			(end 0.2794 -0.1016)
			(stroke
				(width 0.1)
				(type default)
			)
			(layer "F.Fab")
		)
		(fp_line
			(start 0.2794 -0.1016)
			(end -0.2794 -0.1016)
			(stroke
				(width 0.1)
				(type default)
			)
			(layer "F.Fab")
		)
		(fp_line
			(start -0.2794 0.9906)
			(end 0.2794 0.9906)
			(stroke
				(width 0.1)
				(type default)
			)
			(layer "F.Fab")
		)
		(fp_line
			(start -0.2794 -0.1016)
			(end -0.2794 0.9906)
			(stroke
				(width 0.1)
				(type default)
			)
			(layer "F.Fab")
		)
		(pad "1" smd rect
			(at 0 0 180)
			(size 0.508 0.508)
			(layers "F.Cu" "F.Mask" "F.Paste")
			(net "BMC_M_MALERT_N")
		)
		(pad "2" smd rect
			(at 0 0.889 180)
			(size 0.508 0.508)
			(layers "F.Cu" "F.Mask" "F.Paste")
			(net "P1V2_AUX_BMC")
		)
		(zone
			(layer "F.Cu")
			(hatch none 0.5)
			(connect_pads
				(clearance 0)
			)
			(min_thickness 0.25)
			(keepout
				(tracks not_allowed)
				(vias allowed)
				(pads allowed)
				(copperpour not_allowed)
				(footprints allowed)
			)
			(placement
				(enabled no)
				(sheetname "")
			)
			(fill
				(thermal_gap 0.5)
				(thermal_bridge_width 0.5)
				(island_removal_mode 0)
			)
			(polygon
				(pts
					(xy 435.642766 -43.721274) (xy 435.134766 -43.721274) (xy 435.134766 -43.340274) (xy 435.642766 -43.340274)
				)
			)
		)
		(zone
			(layer "F.Cu")
			(hatch none 0.5)
			(connect_pads
				(clearance 0)
			)
			(min_thickness 0.25)
			(keepout
				(tracks allowed)
				(vias not_allowed)
				(pads allowed)
				(copperpour not_allowed)
				(footprints allowed)
			)
			(placement
				(enabled no)
				(sheetname "")
			)
			(fill
				(thermal_gap 0.5)
				(thermal_bridge_width 0.5)
				(island_removal_mode 0)
			)
			(polygon
				(pts
					(xy 435.642766 -43.340274) (xy 435.134766 -43.340274) (xy 435.134766 -43.721274) (xy 435.642766 -43.721274)
				)
			)
		)
	)
	(footprint ""
		(layer "F.Cu")
		(at 18.669 -70.866)
		(property "Reference" "C1D25"
			(at 0 0 0)
			(layer "F.SilkS")
			(hide yes)
			(effects
				(font
					(size 1.27 1.27)
				)
			)
		)
		(property "Value" ""
			(at 0 0 0)
			(layer "F.Fab")
			(effects
				(font
					(size 1.27 1.27)
				)
			)
		)
		(duplicate_pad_numbers_are_jumpers no)
		(fp_poly
			(pts
				(xy 0.3048 -0.1016) (xy 0.3048 0.9906) (xy -0.3048 0.9906) (xy -0.3048 -0.1016)
			)
			(stroke
				(width 0)
				(type default)
			)
			(fill no)
			(layer "F.CrtYd")
		)
		(fp_line
			(start -0.3048 -0.1016)
			(end -0.3048 0.9906)
			(stroke
				(width 0.1)
				(type default)
			)
			(layer "F.Fab")
		)
		(fp_line
			(start -0.3048 0.9906)
			(end 0.3048 0.9906)
			(stroke
				(width 0.1)
				(type default)
			)
			(layer "F.Fab")
		)
		(fp_line
			(start 0.3048 -0.1016)
			(end -0.3048 -0.1016)
			(stroke
				(width 0.1)
				(type default)
			)
			(layer "F.Fab")
		)
		(fp_line
			(start 0.3048 0.9906)
			(end 0.3048 -0.1016)
			(stroke
				(width 0.1)
				(type default)
			)
			(layer "F.Fab")
		)
		(pad "1" smd rect
			(at 0 0)
			(size 0.508 0.508)
			(layers "F.Cu" "F.Mask" "F.Paste")
			(net "P12V_HSC_VCC")
		)
		(pad "2" smd rect
			(at 0 0.889)
			(size 0.508 0.508)
			(layers "F.Cu" "F.Mask" "F.Paste")
			(net "AGND_HSC")
		)
		(zone
			(layer "F.Cu")
			(hatch none 0.5)
			(connect_pads
				(clearance 0)
			)
			(min_thickness 0.25)
			(keepout
				(tracks allowed)
				(vias not_allowed)
				(pads allowed)
				(copperpour not_allowed)
				(footprints allowed)
			)
			(placement
				(enabled no)
				(sheetname "")
			)
			(fill
				(thermal_gap 0.5)
				(thermal_bridge_width 0.5)
				(island_removal_mode 0)
			)
			(polygon
				(pts
					(xy 18.415 -70.612) (xy 18.923 -70.612) (xy 18.923 -70.231) (xy 18.415 -70.231)
				)
			)
		)
		(zone
			(layer "F.Cu")
			(hatch none 0.5)
			(connect_pads
				(clearance 0)
			)
			(min_thickness 0.25)
			(keepout
				(tracks not_allowed)
				(vias allowed)
				(pads allowed)
				(copperpour not_allowed)
				(footprints allowed)
			)
			(placement
				(enabled no)
				(sheetname "")
			)
			(fill
				(thermal_gap 0.5)
				(thermal_bridge_width 0.5)
				(island_removal_mode 0)
			)
			(polygon
				(pts
					(xy 18.415 -70.231) (xy 18.923 -70.231) (xy 18.923 -70.612) (xy 18.415 -70.612)
				)
			)
		)
	)
	(footprint ""
		(layer "F.Cu")
		(at 205.036928 -81.415382)
		(property "Reference" "L4D1"
			(at 3.378708 -4.251706 0)
			(unlocked yes)
			(layer "F.SilkS")
			(effects
				(font
					(size 0.4064 0.254)
					(thickness 0.1524)
				)
			)
		)
		(property "Value" ""
			(at 0 0 0)
			(layer "F.Fab")
			(effects
				(font
					(size 1.27 1.27)
				)
			)
		)
		(duplicate_pad_numbers_are_jumpers no)
		(fp_line
			(start -1.1303 -3.199892)
			(end 8.3693 -3.199892)
			(stroke
				(width 0.1524)
				(type default)
			)
			(layer "F.SilkS")
		)
		(fp_line
			(start -1.1303 -1.6637)
			(end -1.1303 -3.199892)
			(stroke
				(width 0.1524)
				(type default)
			)
			(layer "F.SilkS")
		)
		(fp_line
			(start -1.1303 3.199892)
			(end -1.1303 1.6637)
			(stroke
				(width 0.1524)
				(type default)
			)
			(layer "F.SilkS")
		)
		(fp_line
			(start 8.3693 -3.199892)
			(end 8.3693 -1.6637)
			(stroke
				(width 0.1524)
				(type default)
			)
			(layer "F.SilkS")
		)
		(fp_line
			(start 8.3693 1.6637)
			(end 8.3693 3.199892)
			(stroke
				(width 0.1524)
				(type default)
			)
			(layer "F.SilkS")
		)
		(fp_line
			(start 8.3693 3.199892)
			(end -1.1303 3.199892)
			(stroke
				(width 0.1524)
				(type default)
			)
			(layer "F.SilkS")
		)
		(fp_rect
			(start -1.1303 3.199892)
			(end 8.3693 -3.199892)
			(stroke
				(width 0)
				(type default)
			)
			(fill no)
			(layer "F.CrtYd")
		)
		(fp_line
			(start -1.1303 -3.199892)
			(end 8.3693 -3.199892)
			(stroke
				(width 0.1)
				(type default)
			)
			(layer "F.Fab")
		)
		(fp_line
			(start -1.1303 3.199892)
			(end -1.1303 -3.199892)
			(stroke
				(width 0.1)
				(type default)
			)
			(layer "F.Fab")
		)
		(fp_line
			(start 8.3693 -3.199892)
			(end 8.3693 3.199892)
			(stroke
				(width 0.1)
				(type default)
			)
			(layer "F.Fab")
		)
		(fp_line
			(start 8.3693 3.199892)
			(end -1.1303 3.199892)
			(stroke
				(width 0.1)
				(type default)
			)
			(layer "F.Fab")
		)
		(pad "1" smd rect
			(at 0 0)
			(size 3.683 2.667)
			(layers "F.Cu" "F.Mask" "F.Paste")
			(net "VR_PVCCIN_CPU0_PHASE4")
		)
		(pad "2" smd rect
			(at 7.239 0)
			(size 3.683 2.667)
			(layers "F.Cu" "F.Mask" "F.Paste")
			(net "PVCCIN_CPU0")
		)
	)
	(footprint ""
		(layer "F.Cu")
		(at 343.789 -22.64156 90)
		(property "Reference" "C7F12"
			(at 0 0 90)
			(layer "F.SilkS")
			(hide yes)
			(effects
				(font
					(size 1.27 1.27)
				)
			)
		)
		(property "Value" ""
			(at 0 0 90)
			(layer "F.Fab")
			(effects
				(font
					(size 1.27 1.27)
				)
			)
		)
		(duplicate_pad_numbers_are_jumpers no)
		(fp_poly
			(pts
				(xy 0.3048 -0.1016) (xy 0.3048 0.9906) (xy -0.3048 0.9906) (xy -0.3048 -0.1016)
			)
			(stroke
				(width 0)
				(type default)
			)
			(fill no)
			(layer "F.CrtYd")
		)
		(fp_line
			(start 0.3048 -0.1016)
			(end -0.3048 -0.1016)
			(stroke
				(width 0.1)
				(type default)
			)
			(layer "F.Fab")
		)
		(fp_line
			(start -0.3048 -0.1016)
			(end -0.3048 0.9906)
			(stroke
				(width 0.1)
				(type default)
			)
			(layer "F.Fab")
		)
		(fp_line
			(start 0.3048 0.9906)
			(end 0.3048 -0.1016)
			(stroke
				(width 0.1)
				(type default)
			)
			(layer "F.Fab")
		)
		(fp_line
			(start -0.3048 0.9906)
			(end 0.3048 0.9906)
			(stroke
				(width 0.1)
				(type default)
			)
			(layer "F.Fab")
		)
		(pad "1" smd rect
			(at 0 0 90)
			(size 0.508 0.508)
			(layers "F.Cu" "F.Mask" "F.Paste")
			(net "VR_COMP_RC_PVPP_ABC")
		)
		(pad "2" smd rect
			(at 0 0.889 90)
			(size 0.508 0.508)
			(layers "F.Cu" "F.Mask" "F.Paste")
			(net "VR_COMP_PVPP_ABC_3")
		)
		(zone
			(layer "F.Cu")
			(hatch none 0.5)
			(connect_pads
				(clearance 0)
			)
			(min_thickness 0.25)
			(keepout
				(tracks allowed)
				(vias not_allowed)
				(pads allowed)
				(copperpour not_allowed)
				(footprints allowed)
			)
			(placement
				(enabled no)
				(sheetname "")
			)
			(fill
				(thermal_gap 0.5)
				(thermal_bridge_width 0.5)
				(island_removal_mode 0)
			)
			(polygon
				(pts
					(xy 344.043 -22.38756) (xy 344.043 -22.89556) (xy 344.424 -22.89556) (xy 344.424 -22.38756)
				)
			)
		)
		(zone
			(layer "F.Cu")
			(hatch none 0.5)
			(connect_pads
				(clearance 0)
			)
			(min_thickness 0.25)
			(keepout
				(tracks not_allowed)
				(vias allowed)
				(pads allowed)
				(copperpour not_allowed)
				(footprints allowed)
			)
			(placement
				(enabled no)
				(sheetname "")
			)
			(fill
				(thermal_gap 0.5)
				(thermal_bridge_width 0.5)
				(island_removal_mode 0)
			)
			(polygon
				(pts
					(xy 344.424 -22.38756) (xy 344.424 -22.89556) (xy 344.043 -22.89556) (xy 344.043 -22.38756)
				)
			)
		)
	)
	(footprint ""
		(layer "F.Cu")
		(at 346.906342 5.168646 -90)
		(property "Reference" "C7G36"
			(at 0 0 270)
			(layer "F.SilkS")
			(hide yes)
			(effects
				(font
					(size 1.27 1.27)
				)
			)
		)
		(property "Value" ""
			(at 0 0 270)
			(layer "F.Fab")
			(effects
				(font
					(size 1.27 1.27)
				)
			)
		)
		(duplicate_pad_numbers_are_jumpers no)
		(fp_rect
			(start -0.3048 0.9906)
			(end 0.3048 -0.1016)
			(stroke
				(width 0)
				(type default)
			)
			(fill no)
			(layer "F.CrtYd")
		)
		(fp_line
			(start -0.3048 0.9906)
			(end 0.3048 0.9906)
			(stroke
				(width 0.1)
				(type default)
			)
			(layer "F.Fab")
		)
		(fp_line
			(start 0.3048 0.9906)
			(end 0.3048 -0.1016)
			(stroke
				(width 0.1)
				(type default)
			)
			(layer "F.Fab")
		)
		(fp_line
			(start -0.3048 -0.1016)
			(end -0.3048 0.9906)
			(stroke
				(width 0.1)
				(type default)
			)
			(layer "F.Fab")
		)
		(fp_line
			(start 0.3048 -0.1016)
			(end -0.3048 -0.1016)
			(stroke
				(width 0.1)
				(type default)
			)
			(layer "F.Fab")
		)
		(pad "1" smd rect
			(at 0 0 270)
			(size 0.508 0.508)
			(layers "F.Cu" "F.Mask" "F.Paste")
			(net "VR_FET_SW_P12V_STBY_PVDDQ_ABC")
		)
		(pad "2" smd rect
			(at 0 0.889 270)
			(size 0.508 0.508)
			(layers "F.Cu" "F.Mask" "F.Paste")
			(net "GND")
		)
		(zone
			(layer "F.Cu")
			(hatch none 0.5)
			(connect_pads
				(clearance 0)
			)
			(min_thickness 0.25)
			(keepout
				(tracks not_allowed)
				(vias allowed)
				(pads allowed)
				(copperpour not_allowed)
				(footprints allowed)
			)
			(placement
				(enabled no)
				(sheetname "")
			)
			(fill
				(thermal_gap 0.5)
				(thermal_bridge_width 0.5)
				(island_removal_mode 0)
			)
			(polygon
				(pts
					(xy 346.271342 4.914646) (xy 346.271342 5.422646) (xy 346.652342 5.422646) (xy 346.652342 4.914646)
				)
			)
		)
		(zone
			(layer "F.Cu")
			(hatch none 0.5)
			(connect_pads
				(clearance 0)
			)
			(min_thickness 0.25)
			(keepout
				(tracks allowed)
				(vias not_allowed)
				(pads allowed)
				(copperpour not_allowed)
				(footprints allowed)
			)
			(placement
				(enabled no)
				(sheetname "")
			)
			(fill
				(thermal_gap 0.5)
				(thermal_bridge_width 0.5)
				(island_removal_mode 0)
			)
			(polygon
				(pts
					(xy 346.271342 4.914646) (xy 346.271342 5.422646) (xy 346.652342 5.422646) (xy 346.652342 4.914646)
				)
			)
		)
	)
	(footprint ""
		(layer "F.Cu")
		(at 8.763 -13.843)
		(property "Reference" "CT33"
			(at -0.8382 -0.67818 0)
			(unlocked yes)
			(layer "F.SilkS")
			(effects
				(font
					(size 0.4064 0.254)
					(thickness 0.1524)
				)
				(justify left)
			)
		)
		(property "Value" ""
			(at 0 0 0)
			(layer "F.Fab")
			(effects
				(font
					(size 1.27 1.27)
				)
			)
		)
		(duplicate_pad_numbers_are_jumpers no)
		(fp_poly
			(pts
				(xy 0.3048 -0.1016) (xy 0.3048 0.9906) (xy -0.3048 0.9906) (xy -0.3048 -0.1016)
			)
			(stroke
				(width 0)
				(type default)
			)
			(fill no)
			(layer "F.CrtYd")
		)
		(fp_line
			(start -0.3048 -0.1016)
			(end -0.3048 0.9906)
			(stroke
				(width 0.1)
				(type default)
			)
			(layer "F.Fab")
		)
		(fp_line
			(start -0.3048 0.9906)
			(end 0.3048 0.9906)
			(stroke
				(width 0.1)
				(type default)
			)
			(layer "F.Fab")
		)
		(fp_line
			(start 0.3048 -0.1016)
			(end -0.3048 -0.1016)
			(stroke
				(width 0.1)
				(type default)
			)
			(layer "F.Fab")
		)
		(fp_line
			(start 0.3048 0.9906)
			(end 0.3048 -0.1016)
			(stroke
				(width 0.1)
				(type default)
			)
			(layer "F.Fab")
		)
		(pad "1" smd rect
			(at 0 0)
			(size 0.508 0.508)
			(layers "F.Cu" "F.Mask" "F.Paste")
			(net "VR_PVDDQ_GHJ_PH2_SW")
		)
		(pad "2" smd rect
			(at 0 0.889)
			(size 0.508 0.508)
			(layers "F.Cu" "F.Mask" "F.Paste")
			(net "VR_PVDDQ_GHJ_PH2_SW_RC")
		)
		(zone
			(layer "F.Cu")
			(hatch none 0.5)
			(connect_pads
				(clearance 0)
			)
			(min_thickness 0.25)
			(keepout
				(tracks allowed)
				(vias not_allowed)
				(pads allowed)
				(copperpour not_allowed)
				(footprints allowed)
			)
			(placement
				(enabled no)
				(sheetname "")
			)
			(fill
				(thermal_gap 0.5)
				(thermal_bridge_width 0.5)
				(island_removal_mode 0)
			)
			(polygon
				(pts
					(xy 8.509 -13.589) (xy 9.017 -13.589) (xy 9.017 -13.208) (xy 8.509 -13.208)
				)
			)
		)
		(zone
			(layer "F.Cu")
			(hatch none 0.5)
			(connect_pads
				(clearance 0)
			)
			(min_thickness 0.25)
			(keepout
				(tracks not_allowed)
				(vias allowed)
				(pads allowed)
				(copperpour not_allowed)
				(footprints allowed)
			)
			(placement
				(enabled no)
				(sheetname "")
			)
			(fill
				(thermal_gap 0.5)
				(thermal_bridge_width 0.5)
				(island_removal_mode 0)
			)
			(polygon
				(pts
					(xy 8.509 -13.208) (xy 9.017 -13.208) (xy 9.017 -13.589) (xy 8.509 -13.589)
				)
			)
		)
	)
	(footprint ""
		(layer "F.Cu")
		(at 182.372 -56.1594 180)
		(property "Reference" "R4E21"
			(at 0 0 180)
			(layer "F.SilkS")
			(hide yes)
			(effects
				(font
					(size 1.27 1.27)
				)
			)
		)
		(property "Value" ""
			(at 0 0 180)
			(layer "F.Fab")
			(effects
				(font
					(size 1.27 1.27)
				)
			)
		)
		(duplicate_pad_numbers_are_jumpers no)
		(fp_poly
			(pts
				(xy -0.2794 -0.1016) (xy 0.2794 -0.1016) (xy 0.2794 0.9906) (xy -0.2794 0.9906)
			)
			(stroke
				(width 0)
				(type default)
			)
			(fill no)
			(layer "F.CrtYd")
		)
		(fp_line
			(start 0.2794 0.9906)
			(end 0.2794 -0.1016)
			(stroke
				(width 0.1)
				(type default)
			)
			(layer "F.Fab")
		)
		(fp_line
			(start 0.2794 -0.1016)
			(end -0.2794 -0.1016)
			(stroke
				(width 0.1)
				(type default)
			)
			(layer "F.Fab")
		)
		(fp_line
			(start -0.2794 0.9906)
			(end 0.2794 0.9906)
			(stroke
				(width 0.1)
				(type default)
			)
			(layer "F.Fab")
		)
		(fp_line
			(start -0.2794 -0.1016)
			(end -0.2794 0.9906)
			(stroke
				(width 0.1)
				(type default)
			)
			(layer "F.Fab")
		)
		(pad "1" smd rect
			(at 0 0 180)
			(size 0.508 0.508)
			(layers "F.Cu" "F.Mask" "F.Paste")
			(net "VR_PVCCIO_CPU1_OCSET")
		)
		(pad "2" smd rect
			(at 0 0.889 180)
			(size 0.508 0.508)
			(layers "F.Cu" "F.Mask" "F.Paste")
			(net "GND")
		)
		(zone
			(layer "F.Cu")
			(hatch none 0.5)
			(connect_pads
				(clearance 0)
			)
			(min_thickness 0.25)
			(keepout
				(tracks not_allowed)
				(vias allowed)
				(pads allowed)
				(copperpour not_allowed)
				(footprints allowed)
			)
			(placement
				(enabled no)
				(sheetname "")
			)
			(fill
				(thermal_gap 0.5)
				(thermal_bridge_width 0.5)
				(island_removal_mode 0)
			)
			(polygon
				(pts
					(xy 182.626 -56.7944) (xy 182.118 -56.7944) (xy 182.118 -56.4134) (xy 182.626 -56.4134)
				)
			)
		)
		(zone
			(layer "F.Cu")
			(hatch none 0.5)
			(connect_pads
				(clearance 0)
			)
			(min_thickness 0.25)
			(keepout
				(tracks allowed)
				(vias not_allowed)
				(pads allowed)
				(copperpour not_allowed)
				(footprints allowed)
			)
			(placement
				(enabled no)
				(sheetname "")
			)
			(fill
				(thermal_gap 0.5)
				(thermal_bridge_width 0.5)
				(island_removal_mode 0)
			)
			(polygon
				(pts
					(xy 182.626 -56.4134) (xy 182.118 -56.4134) (xy 182.118 -56.7944) (xy 182.626 -56.7944)
				)
			)
		)
	)
)
